# S9S_MB_2U (Grand Teton) — schematic netlist excerpt (pin names and nets, part order shuffled) for the footprints in the layout excerpt that follows; sources: Cadence DE-HDL packaged netlist, KiCad conversion of 03242023_DA0F0TMBIJ0_F0T_Motherboard_J_brd_V01_OCP.brd

J3  SCONN288_ADR50017P130CC  SCONN288_ADR50017-P130CC IO  pkg DDR288S_1-1VXB  page 84
  VIN_BULK0  = P12V_S3_AUX_CPU0_NVDIMM
  RFU0  = TP_CHB_CPU0_DIMM1_FRU_0
  VIN_MGMT  = P3V3_AUX
  HSCL  = I3C_SPD_DDRABCD_CPU0_LVC1_SCL_2
  HSDA  = I3C_SPD_DDRABCD_CPU0_LVC1_SDA
  VSS0  = GND
  DQ0_A  = M_B_CPU0_SA_DQ<0>
  VSS1  = GND
  DQ1_A  = M_B_CPU0_SA_DQ<1>
  VSS2  = GND
  DQS0_A_T  = M_B_CPU0_SA_DQS_DP<0>
  DQS0_A_C  = M_B_CPU0_SA_DQS_DN<0>
  VSS3  = GND
  DQ4_A  = M_B_CPU0_SA_DQ<4>
  VSS4  = GND
  DQ5_A  = M_B_CPU0_SA_DQ<5>
  VSS5  = GND
  DQ8_A  = M_B_CPU0_SA_DQ<8>
  VSS6  = GND
  DQ9_A  = M_B_CPU0_SA_DQ<9>
  VSS7  = GND
  DQS1_A_T  = M_B_CPU0_SA_DQS_DP<1>
  DQS1_A_C  = M_B_CPU0_SA_DQS_DN<1>
  VSS8  = GND
  DQ12_A  = M_B_CPU0_SA_DQ<12>
  VSS9  = GND
  DQ13_A  = M_B_CPU0_SA_DQ<13>
  VSS10  = GND
  DQ16_A  = M_B_CPU0_SA_DQ<16>
  VSS11  = GND
  DQ17_A  = M_B_CPU0_SA_DQ<17>
  VSS12  = GND
  DQS2_A_T  = M_B_CPU0_SA_DQS_DP<2>
  DQS2_A_C  = M_B_CPU0_SA_DQS_DN<2>
  VSS13  = GND
  DQ20_A  = M_B_CPU0_SA_DQ<20>
  VSS14  = GND
  DQ21_A  = M_B_CPU0_SA_DQ<21>
  VSS15  = GND
  DQ24_A  = M_B_CPU0_SA_DQ<24>
  VSS16  = GND
  DQ25_A  = M_B_CPU0_SA_DQ<25>
  VSS17  = GND
  DQS3_A_T  = M_B_CPU0_SA_DQS_DP<3>
  DQS3_A_C  = M_B_CPU0_SA_DQS_DN<3>
  VSS18  = GND
  DQ28_A  = M_B_CPU0_SA_DQ<28>
  VSS19  = GND
  DQ29_A  = M_B_CPU0_SA_DQ<29>
  VSS20  = GND
  CB0_A  = M_B_CPU0_SA_CB<0>
  VSS21  = GND
  CB1_A  = M_B_CPU0_SA_CB<1>
  VSS22  = GND
  DQS4_A_T  = M_B_CPU0_SA_DQS_DP<4>
  DQS4_A_C  = M_B_CPU0_SA_DQS_DN<4>
  VSS23  = GND
  CB4_A  = M_B_CPU0_SA_CB<4>
  VSS24  = GND
  CB5_A  = M_B_CPU0_SA_CB<5>
  VSS25  = GND
  ALERT_N  = M_B_CPU0_ALERT_N
  VSS26  = GND
  CS0_A_N  = M_B_CPU0_SA_CS_N<0>
  VSS27  = GND
  CA0_A  = M_B_CPU0_SA_CA<0>
  VSS28  = GND
  CA2_A  = M_B_CPU0_SA_CA<2>
  VSS29  = GND
  CA4_A  = M_B_CPU0_SA_CA<4>
  VSS30  = GND
  CA6_A  = M_B_CPU0_SA_CA<6>
  VSS31  = GND
  PAR_A  = M_B_CPU0_SA_PAR
  VSS32  = GND
  CA0_B  = M_B_CPU0_SB_CA<0>
  VSS33  = GND
  CA2_B  = M_B_CPU0_SB_CA<2>
  VSS34  = GND
  CA4_B  = M_B_CPU0_SB_CA<4>
  VSS35  = GND
  CA6_B  = M_B_CPU0_SB_CA<6>
  VSS36  = GND
  CS0_B_N  = M_B_CPU0_SB_CS_N<0>
  VSS37  = GND
  \lbd||rsp_a_n\  = M_B_CPU0_SA_RSP<0>
  \lbs||rsp_b_n\  = M_B_CPU0_SB_RSP<0>
  VSS38  = GND
  CB4_B  = M_B_CPU0_SB_CB<4>
  VSS39  = GND
  CB5_B  = M_B_CPU0_SB_CB<5>
  VSS40  = GND
  \dqs9_b_t||tdqs9_b_t||dbi4_b_n\  = M_B_CPU0_SB_DQS_DP<9>
  \dqs9_b_c||tdqs9_b_c\  = M_B_CPU0_SB_DQS_DN<9>
  VSS41  = GND
  CB0_B  = M_B_CPU0_SB_CB<0>
  VSS42  = GND
  CB1_B  = M_B_CPU0_SB_CB<1>
  VSS43  = GND
  DQ0_B  = M_B_CPU0_SB_DQ<0>
  VSS44  = GND
  DQ1_B  = M_B_CPU0_SB_DQ<1>
  VSS45  = GND
  DQS0_B_T  = M_B_CPU0_SB_DQS_DP<0>
  DQS0_B_C  = M_B_CPU0_SB_DQS_DN<0>
  VSS46  = GND
  DQ4_B  = M_B_CPU0_SB_DQ<4>
  VSS47  = GND
  DQ5_B  = M_B_CPU0_SB_DQ<5>
  VSS48  = GND
  DQ8_B  = M_B_CPU0_SB_DQ<8>
  VSS49  = GND
  DQ9_B  = M_B_CPU0_SB_DQ<9>
  VSS50  = GND
  DQS1_B_T  = M_B_CPU0_SB_DQS_DP<1>
  DQS1_B_C  = M_B_CPU0_SB_DQS_DN<1>
  VSS51  = GND
  DQ12_B  = M_B_CPU0_SB_DQ<12>
  VSS52  = GND
  DQ13_B  = M_B_CPU0_SB_DQ<13>
  VSS53  = GND
  DQ16_B  = M_B_CPU0_SB_DQ<16>
  VSS54  = GND
  DQ17_B  = M_B_CPU0_SB_DQ<17>
  VSS55  = GND
  DQS2_B_T  = M_B_CPU0_SB_DQS_DP<2>
  DQS2_B_C  = M_B_CPU0_SB_DQS_DN<2>
  VSS56  = GND
  DQ20_B  = M_B_CPU0_SB_DQ<20>
  VSS57  = GND
  DQ21_B  = M_B_CPU0_SB_DQ<21>
  VSS58  = GND
  DQ24_B  = M_B_CPU0_SB_DQ<24>
  VSS59  = GND
  DQ25_B  = M_B_CPU0_SB_DQ<25>
  VSS60  = GND
  DQS3_B_T  = M_B_CPU0_SB_DQS_DP<3>
  DQS3_B_C  = M_B_CPU0_SB_DQS_DN<3>
  VSS61  = GND
  DQ28_B  = M_B_CPU0_SB_DQ<28>
  VSS62  = GND
  DQ29_B  = M_B_CPU0_SB_DQ<29>
  VSS63  = GND
  RFU1  = TP_CHB_CPU0_DIMM1_FRU_1
  VIN_BULK1  = P12V_S3_AUX_CPU0_NVDIMM
  VIN_BULK2  = P12V_S3_AUX_CPU0_NVDIMM
  \pwr_good||fail_n\  = PWRGD_CHB_CPU0_DIMM1
  HSA  = PD_CHB_CPU0_DIMM1_SAA
  RFU2  = TP_CHB_CPU0_DIMM1_FRU_2
  RFU3  = TP_CHB_CPU0_DIMM1_FRU_3
  VSS64  = GND
  DQ2_A  = M_B_CPU0_SA_DQ<2>
  VSS65  = GND
  DQ3_A  = M_B_CPU0_SA_DQ<3>
  VSS66  = GND
  \dqs5_a_c||tdqs5_a_c||dqs5_a_t||tdqs5_a_t\  = M_B_CPU0_SA_DQS_DN<5>
  \dqs5_a_t||tdqs5_a_t\  = M_B_CPU0_SA_DQS_DP<5>
  VSS67  = GND
  DQ6_A  = M_B_CPU0_SA_DQ<6>
  VSS68  = GND
  DQ7_A  = M_B_CPU0_SA_DQ<7>
  VSS69  = GND
  DQ10_A  = M_B_CPU0_SA_DQ<10>
  VSS70  = GND
  DQ11_A  = M_B_CPU0_SA_DQ<11>
  VSS71  = GND
  \dqs6_a_c||tdqs6_a_c||dqs6_a_t||tdqs6_a_t\  = M_B_CPU0_SA_DQS_DN<6>
  \dqs6_a_t||tdqs6_a_t\  = M_B_CPU0_SA_DQS_DP<6>
  VSS72  = GND
  DQ14_A  = M_B_CPU0_SA_DQ<14>
  VSS73  = GND
  DQ15_A  = M_B_CPU0_SA_DQ<15>
  VSS74  = GND
  DQ18_A  = M_B_CPU0_SA_DQ<18>
  VSS75  = GND
  DQ19_A  = M_B_CPU0_SA_DQ<19>
  VSS76  = GND
  \dqs7_a_c||tdqs7_a_c\  = M_B_CPU0_SA_DQS_DN<7>
  \dqs7_a_t||tdqs7_a_t\  = M_B_CPU0_SA_DQS_DP<7>
  VSS77  = GND
  DQ22_A  = M_B_CPU0_SA_DQ<22>
  VSS78  = GND
  DQ23_A  = M_B_CPU0_SA_DQ<23>
  VSS79  = GND
  DQ26_A  = M_B_CPU0_SA_DQ<26>
  VSS80  = GND
  DQ27_A  = M_B_CPU0_SA_DQ<27>
  VSS81  = GND
  \dqs8_a_c||tdqs8_a_c\  = M_B_CPU0_SA_DQS_DN<8>
  \dqs8_a_t||tdqs8_a_t\  = M_B_CPU0_SA_DQS_DP<8>
  VSS82  = GND
  DQ30_A  = M_B_CPU0_SA_DQ<30>
  VSS83  = GND
  DQ31_A  = M_B_CPU0_SA_DQ<31>
  VSS84  = GND
  CB2_A  = M_B_CPU0_SA_CB<2>
  VSS85  = GND
  CB3_A  = M_B_CPU0_SA_CB<3>
  VSS86  = GND
  \dqs9_a_c||tdqs9_a_c\  = M_B_CPU0_SA_DQS_DN<9>
  \dqs9_a_t||tdqs9_a_t\  = M_B_CPU0_SA_DQS_DP<9>
  VSS87  = GND
  CB6_A  = M_B_CPU0_SA_CB<6>
  VSS88  = GND
  CB7_A  = M_B_CPU0_SA_CB<7>
  VSS89  = GND
  RESET_N  = RST_M_AB_CPU0_FPGA_N
  VSS90  = GND
  CS1_A_N  = M_B_CPU0_SA_CS_N<1>
  VSS91  = GND
  CA1_A  = M_B_CPU0_SA_CA<1>
  VSS92  = GND
  CA3_A  = M_B_CPU0_SA_CA<3>
  VSS93  = GND
  CA5_A  = M_B_CPU0_SA_CA<5>
  VSS94  = GND
  CK_T  = M_B_CPU0_CLK_DP<0>
  CK_C  = M_B_CPU0_CLK_DN<0>
  VSS95  = GND
  RFU4  = TP_CHB_CPU0_DIMM1_FRU_4
  CA1_B  = M_B_CPU0_SB_CA<1>
  VSS96  = GND
  CA3_B  = M_B_CPU0_SB_CA<3>
  VSS97  = GND
  CA5_B  = M_B_CPU0_SB_CA<5>
  VSS98  = GND
  PAR_B  = M_B_CPU0_SB_PAR
  VSS99  = GND
  CS1_B_N  = M_B_CPU0_SB_CS_N<1>
  VSS100  = GND
  RFU5  = TP_CHB_CPU0_DIMM1_FRU_5
  RFU6  = TP_CHB_CPU0_DIMM1_FRU_6
  VSS101  = GND
  CB6_B  = M_B_CPU0_SB_CB<6>
  VSS102  = GND
  CB7_B  = M_B_CPU0_SB_CB<7>
  VSS103  = GND
  DQS4_B_C  = M_B_CPU0_SB_DQS_DN<4>
  DQS4_B_T  = M_B_CPU0_SB_DQS_DP<4>
  VSS104  = GND
  CB2_B  = M_B_CPU0_SB_CB<2>
  VSS105  = GND
  CB3_B  = M_B_CPU0_SB_CB<3>
  VSS106  = GND
  DQ2_B  = M_B_CPU0_SB_DQ<2>
  VSS107  = GND
  DQ3_B  = M_B_CPU0_SB_DQ<3>
  VSS108  = GND
  \dqs5_b_c||tdqs5_b_c\  = M_B_CPU0_SB_DQS_DN<5>
  \dqs5_b_t||tdqs5_b_t\  = M_B_CPU0_SB_DQS_DP<5>
  VSS109  = GND
  DQ6_B  = M_B_CPU0_SB_DQ<6>
  VSS110  = GND
  DQ7_B  = M_B_CPU0_SB_DQ<7>
  VSS111  = GND
  DQ10_B  = M_B_CPU0_SB_DQ<10>
  VSS112  = GND
  DQ11_B  = M_B_CPU0_SB_DQ<11>
  VSS113  = GND
  \dqs6_b_c||tdqs6_b_c\  = M_B_CPU0_SB_DQS_DN<6>
  \dqs6_b_t||tdqs6_b_t\  = M_B_CPU0_SB_DQS_DP<6>
  VSS114  = GND
  DQ14_B  = M_B_CPU0_SB_DQ<14>
  VSS115  = GND
  DQ15_B  = M_B_CPU0_SB_DQ<15>
  VSS116  = GND
  DQ18_B  = M_B_CPU0_SB_DQ<18>
  VSS117  = GND
  DQ19_B  = M_B_CPU0_SB_DQ<19>
  VSS118  = GND
  \dqs7_b_c||tdqs7_b_c\  = M_B_CPU0_SB_DQS_DN<7>
  \dqs7_b_t||tdqs7_b_t\  = M_B_CPU0_SB_DQS_DP<7>
  VSS119  = GND
  DQ22_B  = M_B_CPU0_SB_DQ<22>
  VSS120  = GND
  DQ23_B  = M_B_CPU0_SB_DQ<23>
  VSS121  = GND
  DQ26_B  = M_B_CPU0_SB_DQ<26>
  VSS122  = GND
  DQ27_B  = M_B_CPU0_SB_DQ<27>
  VSS123  = GND
  \dqs8_b_c||tdqs8_b_c\  = M_B_CPU0_SB_DQS_DN<8>
  \dqs8_b_t||tdqs8_b_t\  = M_B_CPU0_SB_DQS_DP<8>
  VSS124  = GND
  DQ30_B  = M_B_CPU0_SB_DQ<30>
  VSS125  = GND
  DQ31_B  = M_B_CPU0_SB_DQ<31>
  VSS126  = GND
  G1  = GND
  G2  = GND
  G3  = GND

(kicad_pcb
	(version 20260206)
	(generator "pcbnew")
	(generator_version "10.0")
	(general
		(thickness 1.6)
		(legacy_teardrops no)
	)
	(paper "A4")
	(title_block
		(title "03242023_DA0F0TMBIJ0_F0T_Motherboard_J_brd_V01_OCP.brd")
		(comment 1 "Grand Teton / footprint 2048 of 6105 (J3), pads 92-137 of 291")
	)
	(layers
		(0 "F.Cu" signal "TOP")
		(4 "In1.Cu" signal "GND")
		(6 "In2.Cu" signal "IN1")
		(8 "In3.Cu" signal "GND1")
		(10 "In4.Cu" signal "IN2")
		(12 "In5.Cu" signal "GND2")
		(14 "In6.Cu" signal "IN3")
		(16 "In7.Cu" signal "GND3")
		(18 "In8.Cu" signal "VCC")
		(20 "In9.Cu" signal "VCC1")
		(22 "In10.Cu" signal "GND4")
		(24 "In11.Cu" signal "IN4")
		(26 "In12.Cu" signal "GND5")
		(28 "In13.Cu" signal "IN5")
		(30 "In14.Cu" signal "GND6")
		(32 "In15.Cu" signal "IN6")
		(34 "In16.Cu" signal "GND7")
		(2 "B.Cu" signal "BOTTOM")
		(9 "F.Adhes" user "F.Adhesive")
		(11 "B.Adhes" user "B.Adhesive")
		(13 "F.Paste" user "Package Geometry/Pastemask Top")
		(15 "B.Paste" user "Package Geometry/Pastemask Bottom")
		(5 "F.SilkS" user "Ref Des/Silkscreen Top")
		(7 "B.SilkS" user "Ref Des/Silkscreen Bottom")
		(1 "F.Mask" user "Board Geometry/Soldermask Top")
		(3 "B.Mask" user "Board Geometry/Soldermask Bottom")
		(17 "Dwgs.User" user "User.Drawings")
		(19 "Cmts.User" user "User.Comments")
		(21 "Eco1.User" user "User.Eco1")
		(23 "Eco2.User" user "User.Eco2")
		(25 "Edge.Cuts" user "Board Geometry/Outline")
		(27 "Margin" user)
		(31 "F.CrtYd" user "Package Geometry/Place Bound Top")
		(29 "B.CrtYd" user "Package Geometry/Place Bound Bottom")
		(35 "F.Fab" user "Ref Des/Assembly Top")
		(33 "B.Fab" user "Ref Des/Assembly Bottom")
	)
	(footprint ""
		(layer "F.Cu")
		(at 288.305748 -258.091686)
		(property "Reference" "J3"
			(at -3.683 -81.702148 0)
			(unlocked yes)
			(layer "F.SilkS")
			(effects
				(font
					(size 0.7874 0.5842)
					(thickness 0.1524)
				)
				(justify left)
			)
		)
		(property "Value" ""
			(at 0 0 0)
			(layer "F.Fab")
			(effects
				(font
					(size 1.27 1.27)
				)
			)
		)
		(duplicate_pad_numbers_are_jumpers no)
		(pad "92" smd rect
			(at -2.050034 19.12493 270)
			(size 0.519938 1.4986)
			(layers "F.Cu" "F.Mask" "F.Paste")
			(net "GND")
		)
		(pad "93" smd rect
			(at -2.050034 19.975068 270)
			(size 0.519938 1.4986)
			(layers "F.Cu" "F.Mask" "F.Paste")
			(net "M_B_CPU0_SB_DQS_DP<9>")
		)
		(pad "94" smd rect
			(at -2.050034 20.824952 270)
			(size 0.519938 1.4986)
			(layers "F.Cu" "F.Mask" "F.Paste")
			(net "M_B_CPU0_SB_DQS_DN<9>")
		)
		(pad "95" smd rect
			(at -2.050034 21.67509 270)
			(size 0.519938 1.4986)
			(layers "F.Cu" "F.Mask" "F.Paste")
			(net "GND")
		)
		(pad "96" smd rect
			(at -2.050034 22.524974 270)
			(size 0.519938 1.4986)
			(layers "F.Cu" "F.Mask" "F.Paste")
			(net "M_B_CPU0_SB_CB<0>")
		)
		(pad "97" smd rect
			(at -2.050034 23.375112 270)
			(size 0.519938 1.4986)
			(layers "F.Cu" "F.Mask" "F.Paste")
			(net "GND")
		)
		(pad "98" smd rect
			(at -2.050034 24.224996 270)
			(size 0.519938 1.4986)
			(layers "F.Cu" "F.Mask" "F.Paste")
			(net "M_B_CPU0_SB_CB<1>")
		)
		(pad "99" smd rect
			(at -2.050034 25.07488 270)
			(size 0.519938 1.4986)
			(layers "F.Cu" "F.Mask" "F.Paste")
			(net "GND")
		)
		(pad "100" smd rect
			(at -2.050034 25.925018 270)
			(size 0.519938 1.4986)
			(layers "F.Cu" "F.Mask" "F.Paste")
			(net "M_B_CPU0_SB_DQ<0>")
		)
		(pad "101" smd rect
			(at -2.050034 26.774902 270)
			(size 0.519938 1.4986)
			(layers "F.Cu" "F.Mask" "F.Paste")
			(net "GND")
		)
		(pad "102" smd rect
			(at -2.050034 27.62504 270)
			(size 0.519938 1.4986)
			(layers "F.Cu" "F.Mask" "F.Paste")
			(net "M_B_CPU0_SB_DQ<1>")
		)
		(pad "103" smd rect
			(at -2.050034 28.474924 270)
			(size 0.519938 1.4986)
			(layers "F.Cu" "F.Mask" "F.Paste")
			(net "GND")
		)
		(pad "104" smd rect
			(at -2.050034 29.325062 270)
			(size 0.519938 1.4986)
			(layers "F.Cu" "F.Mask" "F.Paste")
			(net "M_B_CPU0_SB_DQS_DP<0>")
		)
		(pad "105" smd rect
			(at -2.050034 30.174946 270)
			(size 0.519938 1.4986)
			(layers "F.Cu" "F.Mask" "F.Paste")
			(net "M_B_CPU0_SB_DQS_DN<0>")
		)
		(pad "106" smd rect
			(at -2.050034 31.025084 270)
			(size 0.519938 1.4986)
			(layers "F.Cu" "F.Mask" "F.Paste")
			(net "GND")
		)
		(pad "107" smd rect
			(at -2.050034 31.874968 270)
			(size 0.519938 1.4986)
			(layers "F.Cu" "F.Mask" "F.Paste")
			(net "M_B_CPU0_SB_DQ<4>")
		)
		(pad "108" smd rect
			(at -2.050034 32.725106 270)
			(size 0.519938 1.4986)
			(layers "F.Cu" "F.Mask" "F.Paste")
			(net "GND")
		)
		(pad "109" smd rect
			(at -2.050034 33.57499 270)
			(size 0.519938 1.4986)
			(layers "F.Cu" "F.Mask" "F.Paste")
			(net "M_B_CPU0_SB_DQ<5>")
		)
		(pad "110" smd rect
			(at -2.050034 34.425128 270)
			(size 0.519938 1.4986)
			(layers "F.Cu" "F.Mask" "F.Paste")
			(net "GND")
		)
		(pad "111" smd rect
			(at -2.050034 35.275012 270)
			(size 0.519938 1.4986)
			(layers "F.Cu" "F.Mask" "F.Paste")
			(net "M_B_CPU0_SB_DQ<8>")
		)
		(pad "112" smd rect
			(at -2.050034 36.124896 270)
			(size 0.519938 1.4986)
			(layers "F.Cu" "F.Mask" "F.Paste")
			(net "GND")
		)
		(pad "113" smd rect
			(at -2.050034 36.975034 270)
			(size 0.519938 1.4986)
			(layers "F.Cu" "F.Mask" "F.Paste")
			(net "M_B_CPU0_SB_DQ<9>")
		)
		(pad "114" smd rect
			(at -2.050034 37.824918 270)
			(size 0.519938 1.4986)
			(layers "F.Cu" "F.Mask" "F.Paste")
			(net "GND")
		)
		(pad "115" smd rect
			(at -2.050034 38.675056 270)
			(size 0.519938 1.4986)
			(layers "F.Cu" "F.Mask" "F.Paste")
			(net "M_B_CPU0_SB_DQS_DP<1>")
		)
		(pad "116" smd rect
			(at -2.050034 39.52494 270)
			(size 0.519938 1.4986)
			(layers "F.Cu" "F.Mask" "F.Paste")
			(net "M_B_CPU0_SB_DQS_DN<1>")
		)
		(pad "117" smd rect
			(at -2.050034 40.375078 270)
			(size 0.519938 1.4986)
			(layers "F.Cu" "F.Mask" "F.Paste")
			(net "GND")
		)
		(pad "118" smd rect
			(at -2.050034 41.224962 270)
			(size 0.519938 1.4986)
			(layers "F.Cu" "F.Mask" "F.Paste")
			(net "M_B_CPU0_SB_DQ<12>")
		)
		(pad "119" smd rect
			(at -2.050034 42.0751 270)
			(size 0.519938 1.4986)
			(layers "F.Cu" "F.Mask" "F.Paste")
			(net "GND")
		)
		(pad "120" smd rect
			(at -2.050034 42.924984 270)
			(size 0.519938 1.4986)
			(layers "F.Cu" "F.Mask" "F.Paste")
			(net "M_B_CPU0_SB_DQ<13>")
		)
		(pad "121" smd rect
			(at -2.050034 43.775122 270)
			(size 0.519938 1.4986)
			(layers "F.Cu" "F.Mask" "F.Paste")
			(net "GND")
		)
		(pad "122" smd rect
			(at -2.050034 44.625006 270)
			(size 0.519938 1.4986)
			(layers "F.Cu" "F.Mask" "F.Paste")
			(net "M_B_CPU0_SB_DQ<16>")
		)
		(pad "123" smd rect
			(at -2.050034 45.47489 270)
			(size 0.519938 1.4986)
			(layers "F.Cu" "F.Mask" "F.Paste")
			(net "GND")
		)
		(pad "124" smd rect
			(at -2.050034 46.325028 270)
			(size 0.519938 1.4986)
			(layers "F.Cu" "F.Mask" "F.Paste")
			(net "M_B_CPU0_SB_DQ<17>")
		)
		(pad "125" smd rect
			(at -2.050034 47.174912 270)
			(size 0.519938 1.4986)
			(layers "F.Cu" "F.Mask" "F.Paste")
			(net "GND")
		)
		(pad "126" smd rect
			(at -2.050034 48.02505 270)
			(size 0.519938 1.4986)
			(layers "F.Cu" "F.Mask" "F.Paste")
			(net "M_B_CPU0_SB_DQS_DP<2>")
		)
		(pad "127" smd rect
			(at -2.050034 48.874934 270)
			(size 0.519938 1.4986)
			(layers "F.Cu" "F.Mask" "F.Paste")
			(net "M_B_CPU0_SB_DQS_DN<2>")
		)
		(pad "128" smd rect
			(at -2.050034 49.725072 270)
			(size 0.519938 1.4986)
			(layers "F.Cu" "F.Mask" "F.Paste")
			(net "GND")
		)
		(pad "129" smd rect
			(at -2.050034 50.574956 270)
			(size 0.519938 1.4986)
			(layers "F.Cu" "F.Mask" "F.Paste")
			(net "M_B_CPU0_SB_DQ<20>")
		)
		(pad "130" smd rect
			(at -2.050034 51.425094 270)
			(size 0.519938 1.4986)
			(layers "F.Cu" "F.Mask" "F.Paste")
			(net "GND")
		)
		(pad "131" smd rect
			(at -2.050034 52.274978 270)
			(size 0.519938 1.4986)
			(layers "F.Cu" "F.Mask" "F.Paste")
			(net "M_B_CPU0_SB_DQ<21>")
		)
		(pad "132" smd rect
			(at -2.050034 53.125116 270)
			(size 0.519938 1.4986)
			(layers "F.Cu" "F.Mask" "F.Paste")
			(net "GND")
		)
		(pad "133" smd rect
			(at -2.050034 53.975 270)
			(size 0.519938 1.4986)
			(layers "F.Cu" "F.Mask" "F.Paste")
			(net "M_B_CPU0_SB_DQ<24>")
		)
		(pad "134" smd rect
			(at -2.050034 54.824884 270)
			(size 0.519938 1.4986)
			(layers "F.Cu" "F.Mask" "F.Paste")
			(net "GND")
		)
		(pad "135" smd rect
			(at -2.050034 55.675022 270)
			(size 0.519938 1.4986)
			(layers "F.Cu" "F.Mask" "F.Paste")
			(net "M_B_CPU0_SB_DQ<25>")
		)
		(pad "136" smd rect
			(at -2.050034 56.524906 270)
			(size 0.519938 1.4986)
			(layers "F.Cu" "F.Mask" "F.Paste")
			(net "GND")
		)
		(pad "137" smd rect
			(at -2.050034 57.375044 270)
			(size 0.519938 1.4986)
			(layers "F.Cu" "F.Mask" "F.Paste")
			(net "M_B_CPU0_SB_DQS_DP<3>")
		)
	)
)
